G04 ================== begin FILE IDENTIFICATION RECORD ==================*
G04 Layout Name:  12433-1M.brd*
G04 Film Name:    GOLD_T*
G04 File Format:  Gerber RS274X*
G04 File Origin:  Cadence Allegro 16.2-S037*
G04 Origin Date:  Fri Dec 07 18:55:10 2012*
G04 *
G04 Layer:  PACKAGE GEOMETRY/GOLDEN_TOP*
G04 Layer:  DRAWING FORMAT/LAYER_GOLD_T*
G04 Layer:  DRAWING FORMAT/LAYER_PCB_STORY*
G04 Layer:  BOARD GEOMETRY/GOLDEN_TOP*
G04 Layer:  BOARD GEOMETRY/PANEL_OUTLINE*
G04 *
G04 Offset:    (0.00 0.00)*
G04 Mirror:    No*
G04 Mode:      Positive*
G04 Rotation:  0*
G04 FullContactRelief:  No*
G04 UndefLineWidth:     6.00*
G04 ================== end FILE IDENTIFICATION RECORD ====================*
%FSLAX35Y35*MOIN*%
%IR0*IPPOS*OFA0.00000B0.00000*MIA0B0*SFA1.00000B1.00000*%
%ADD10C,.02*%
%ADD11C,.006*%
G75*
%LPD*%
G75*
G36*
G01X123426Y1772126D02*
Y1689960D01*
X69488D01*
Y1856890D01*
X123426D01*
Y1785512D01*
X119095D01*
G03Y1772126I0J-6693D01*
G01X123426D01*
G37*
G36*
G01X134448D02*
Y1689960D01*
X188386D01*
Y1856890D01*
X134448D01*
Y1785512D01*
X138779D01*
G02Y1772126I0J-6693D01*
G01X134448D01*
G37*
G54D10*
G01X-448201Y-82763D02*
Y-162763D01*
G01Y-118263D02*
X752899D01*
G01X-448201Y-162763D02*
X752899D01*
G01X-452201Y-66763D02*
G02I-12000J0D01*
G01X-457351D02*
G02I-6850J0D01*
G01X-464201Y-82763D02*
Y-50763D01*
G01X-448201Y-66763D02*
X-480201D01*
G01X-448201Y-82763D02*
X752899D01*
G01X-34601D02*
Y-162763D01*
G01X102899Y-82763D02*
Y-162763D01*
G01X217899Y-82763D02*
Y-162763D01*
G01X385399Y-82763D02*
Y-162763D01*
G01X555399Y-82763D02*
Y-162763D01*
G01X752899Y-82763D02*
Y-162763D01*
G01X780899Y-66763D02*
G02I-12000J0D01*
G01X775749D02*
G02I-6850J0D01*
G01X768899Y-82763D02*
Y-50763D01*
G01X784899Y-66763D02*
X752899D01*
G54D11*
G01X-430254Y-152763D02*
Y-135263D01*
G01X-421958D02*
X-430254Y-146055D01*
G01X-420648Y-152763D02*
X-426543Y-141097D01*
G01X-412973Y-152763D02*
Y-135263D01*
X-402929Y-152763D01*
Y-135263D01*
G01X-390451Y-152763D02*
X-392198Y-152471D01*
X-393726Y-151305D01*
X-395036Y-149555D01*
X-395910Y-147513D01*
X-396346Y-145180D01*
Y-142846D01*
X-395910Y-140513D01*
X-395036Y-138471D01*
X-393726Y-136722D01*
X-392198Y-135555D01*
X-390451Y-135263D01*
X-388705Y-135555D01*
X-387176Y-136722D01*
X-385866Y-138471D01*
X-384992Y-140513D01*
X-384556Y-142846D01*
Y-145180D01*
X-384992Y-147513D01*
X-385866Y-149555D01*
X-387176Y-151305D01*
X-388705Y-152471D01*
X-390451Y-152763D01*
G01X-377536D02*
X-368366Y-135263D01*
G01X-377536D02*
X-368366Y-152763D01*
G01X-362001Y-158596D02*
X-348901D01*
G01X-342099Y-152763D02*
Y-135263D01*
X-333803D01*
G01X-336859Y-143721D02*
X-342099D01*
G01X-325910Y-152763D02*
X-320451Y-135263D01*
X-314992Y-152763D01*
G01X-316958Y-146638D02*
X-323945D01*
G01X-307973Y-152763D02*
Y-135263D01*
X-297929Y-152763D01*
Y-135263D01*
G01X-263148Y-136722D02*
X-264458Y-135846D01*
X-265986Y-135263D01*
X-267733D01*
X-269698Y-136138D01*
X-271226Y-137596D01*
X-272318Y-139347D01*
X-273191Y-142263D01*
X-273410Y-144888D01*
X-272973Y-147513D01*
X-272318Y-149263D01*
X-271008Y-151013D01*
X-269479Y-152180D01*
X-267951Y-152763D01*
X-266423D01*
X-264894Y-152180D01*
X-263584Y-151305D01*
X-262492Y-150139D01*
G01X-250451Y-152763D02*
X-252198Y-152471D01*
X-253726Y-151305D01*
X-255036Y-149555D01*
X-255910Y-147513D01*
X-256346Y-145180D01*
Y-142846D01*
X-255910Y-140513D01*
X-255036Y-138471D01*
X-253726Y-136722D01*
X-252198Y-135555D01*
X-250451Y-135263D01*
X-248705Y-135555D01*
X-247176Y-136722D01*
X-245866Y-138471D01*
X-244992Y-140513D01*
X-244556Y-142846D01*
Y-145180D01*
X-244992Y-147513D01*
X-245866Y-149555D01*
X-247176Y-151305D01*
X-248705Y-152471D01*
X-250451Y-152763D01*
G01X-237973D02*
Y-135263D01*
X-227929Y-152763D01*
Y-135263D01*
G01X-215451D02*
Y-152763D01*
G01X-220473Y-135263D02*
X-210429D01*
G01X-202318Y-152763D02*
Y-135263D01*
X-196859D01*
X-195113Y-136138D01*
X-194021Y-137305D01*
X-193584Y-139638D01*
X-194021Y-141972D01*
X-195331Y-143430D01*
X-196859Y-144305D01*
X-202318D01*
G01X-196859D02*
X-193584Y-152763D01*
G01X-180451D02*
X-182198Y-152471D01*
X-183726Y-151305D01*
X-185036Y-149555D01*
X-185910Y-147513D01*
X-186346Y-145180D01*
Y-142846D01*
X-185910Y-140513D01*
X-185036Y-138471D01*
X-183726Y-136722D01*
X-182198Y-135555D01*
X-180451Y-135263D01*
X-178705Y-135555D01*
X-177176Y-136722D01*
X-175866Y-138471D01*
X-174992Y-140513D01*
X-174556Y-142846D01*
Y-145180D01*
X-174992Y-147513D01*
X-175866Y-149555D01*
X-177176Y-151305D01*
X-178705Y-152471D01*
X-180451Y-152763D01*
G01X-167318Y-135263D02*
Y-152763D01*
X-158584D01*
G01X-126205Y-143430D02*
X-125331Y-142555D01*
X-124676Y-141097D01*
X-124239Y-139054D01*
X-124676Y-137305D01*
X-125549Y-136138D01*
X-127078Y-135263D01*
X-132973D01*
Y-152763D01*
X-125768D01*
X-124239Y-151597D01*
X-123366Y-149846D01*
X-122929Y-147805D01*
X-123366Y-145763D01*
X-124676Y-144013D01*
X-126205Y-143430D01*
X-132973D01*
G01X-110451Y-152763D02*
X-112198Y-152471D01*
X-113726Y-151305D01*
X-115036Y-149555D01*
X-115910Y-147513D01*
X-116346Y-145180D01*
Y-142846D01*
X-115910Y-140513D01*
X-115036Y-138471D01*
X-113726Y-136722D01*
X-112198Y-135555D01*
X-110451Y-135263D01*
X-108705Y-135555D01*
X-107176Y-136722D01*
X-105866Y-138471D01*
X-104992Y-140513D01*
X-104556Y-142846D01*
Y-145180D01*
X-104992Y-147513D01*
X-105866Y-149555D01*
X-107176Y-151305D01*
X-108705Y-152471D01*
X-110451Y-152763D01*
G01X-98410D02*
X-92951Y-135263D01*
X-87492Y-152763D01*
G01X-89458Y-146638D02*
X-96445D01*
G01X-79818Y-152763D02*
Y-135263D01*
X-74359D01*
X-72613Y-136138D01*
X-71521Y-137305D01*
X-71084Y-139638D01*
X-71521Y-141972D01*
X-72831Y-143430D01*
X-74359Y-144305D01*
X-79818D01*
G01X-74359D02*
X-71084Y-152763D01*
G01X-62754D02*
Y-135263D01*
X-58388D01*
X-56641Y-136138D01*
X-55331Y-137305D01*
X-54239Y-139054D01*
X-53366Y-141097D01*
X-53148Y-144013D01*
X-53366Y-146930D01*
X-54239Y-148972D01*
X-55331Y-150722D01*
X-56641Y-151888D01*
X-58388Y-152763D01*
X-62754D01*
G01X-282378Y-107763D02*
Y-90263D01*
X-276701Y-104846D01*
X-271024Y-90263D01*
Y-107763D01*
G01X-259201D02*
X-260511Y-107471D01*
X-261821Y-106305D01*
X-262695Y-104263D01*
X-263131Y-101930D01*
X-262695Y-99596D01*
X-261821Y-97555D01*
X-260511Y-96388D01*
X-259201Y-96097D01*
X-257891Y-96388D01*
X-256581Y-97555D01*
X-255708Y-99596D01*
X-255489Y-101930D01*
X-255708Y-104263D01*
X-256581Y-106305D01*
X-257891Y-107471D01*
X-259201Y-107763D01*
G01X-237771Y-90263D02*
Y-107763D01*
G01Y-105139D02*
X-238644Y-106597D01*
X-239955Y-107471D01*
X-241483Y-107763D01*
X-243229Y-107180D01*
X-244539Y-105722D01*
X-245413Y-103972D01*
X-245631Y-101930D01*
X-245413Y-99888D01*
X-244539Y-98138D01*
X-243229Y-96680D01*
X-241483Y-96097D01*
X-239955Y-96388D01*
X-238863Y-96972D01*
X-237771Y-98138D01*
G01X-227476Y-99888D02*
X-220489D01*
X-221144Y-97846D01*
X-222236Y-96680D01*
X-223764Y-96097D01*
X-225293Y-96388D01*
X-226603Y-97263D01*
X-227476Y-99305D01*
X-227913Y-101055D01*
Y-102805D01*
X-227476Y-104555D01*
X-226384Y-106305D01*
X-225074Y-107471D01*
X-223546Y-107763D01*
X-222018Y-107180D01*
X-220489Y-105430D01*
G01X-206701Y-107763D02*
Y-90263D01*
G01X-242126Y15000D02*
G03X-227126Y0I15000J0D01*
G01X-242126Y1953504D02*
Y15000D01*
G01X-215453Y19685D02*
G03I-6988J0D01*
G01X-84646Y0D02*
X-227126D01*
G01X-215453Y19685D02*
G03I-6988J0D01*
G01D02*
G03I-6988J0D01*
G01X-227126Y1968504D02*
G03X-242126Y1953504I0J-15000D01*
G01X-215453Y1948819D02*
G03I-6988J0D01*
G01X-84638Y1968504D02*
X-227126D01*
G01X-215453Y1948819D02*
G03I-6988J0D01*
G01D02*
G03I-6988J0D01*
G01X-222441Y39370D02*
G03X-214567Y31496I7874J0D01*
G01X-206693D02*
X-214567D01*
G01X-175984D02*
X-84646D01*
G01X-206693D02*
G03Y39370I0J3937D01*
G01X-175984D02*
G03Y31496I0J-3937D01*
G01X-206693D02*
X-214567D01*
G01X-84646Y0D02*
X-199567D01*
G01X-175984Y31496D02*
X-84646D01*
G01X-206693D02*
G03Y39370I0J3937D01*
G01X-175984D02*
G03Y31496I0J-3937D01*
G01X-222441Y169326D02*
Y39370D01*
G01X-214567Y43307D02*
G03X-210630Y39370I3937J0D01*
G01X-214567Y43307D02*
G03X-210630Y39370I3937J0D01*
G01X-80709D02*
X-210630D01*
G01X-80709D02*
X-210630D01*
G01X-214567Y43307D02*
Y1925197D01*
G01Y43307D02*
Y1925197D01*
G01Y149606D02*
Y43307D01*
G01Y149606D02*
Y43272D01*
G01Y169326D02*
G03X-222441I-3937J0D01*
G01X-214567D02*
G03X-222441I-3937J0D01*
G01X-214567Y1807087D02*
Y161417D01*
G01Y1807087D02*
Y161417D01*
G01X-222441Y436255D02*
Y200034D01*
G01D02*
G03X-214567I3937J0D01*
G01X-222441D02*
G03X-214567I3937J0D01*
G01Y436255D02*
G03X-222441I-3937J0D01*
G01X-214567D02*
G03X-222441I-3937J0D01*
G01Y703184D02*
Y466963D01*
G01D02*
G03X-214567I3937J0D01*
G01X-222441D02*
G03X-214567I3937J0D01*
G01X-222441Y970901D02*
Y733892D01*
G01X-214567Y703184D02*
G03X-222441I-3937J0D01*
G01Y733892D02*
G03X-214567I3937J0D01*
G01Y703184D02*
G03X-222441I-3937J0D01*
G01Y733892D02*
G03X-214567I3937J0D01*
G01X-222441Y1234681D02*
Y997672D01*
G01X-214567Y970901D02*
G03X-222441I-3937J0D01*
G01Y997672D02*
G03X-214567I3937J0D01*
G01Y970901D02*
G03X-222441I-3937J0D01*
G01Y997672D02*
G03X-214567I3937J0D01*
G01X-222441Y1265389D02*
G03X-214567I3937J0D01*
G01Y1234681D02*
G03X-222441I-3937J0D01*
G01Y1265389D02*
G03X-214567I3937J0D01*
G01Y1234681D02*
G03X-222441I-3937J0D01*
G01Y1501610D02*
Y1265389D01*
G01X-214567Y1501610D02*
G03X-222441I-3937J0D01*
G01X-214567D02*
G03X-222441I-3937J0D01*
G01Y1768539D02*
Y1532318D01*
G01D02*
G03X-214567I3937J0D01*
G01X-222441D02*
G03X-214567I3937J0D01*
G01Y1768539D02*
G03X-222441I-3937J0D01*
G01X-214567D02*
G03X-222441I-3937J0D01*
G01Y1799247D02*
G03X-214567I3937J0D01*
G01X-222441D02*
G03X-214567I3937J0D01*
G01X-222441Y1929134D02*
Y1799247D01*
G01X-214567Y1818898D02*
Y1925231D01*
G01Y1818898D02*
Y1925231D01*
G01X-210630Y1929134D02*
G03X-214567Y1925197I0J-3937D01*
G01X-210630Y1929134D02*
G03X-214567Y1925197I0J-3937D01*
G01Y1937008D02*
G03X-222441Y1929134I0J-7874D01*
G01X-210630D02*
X-80709D01*
G01X-210630D02*
X-80709D01*
G01X-175984Y1937008D02*
X-84638D01*
G01X-214567D02*
X-206693D01*
G01X-175984D02*
G03Y1929134I0J-3937D01*
G01X-206693D02*
G03Y1937008I0J3937D01*
G01X-84638Y1968504D02*
X-199567D01*
G01X-175984Y1937008D02*
X-84638D01*
G01X-214567D02*
X-206693D01*
G01X-175984D02*
G03Y1929134I0J-3937D01*
G01X-206693D02*
G03Y1937008I0J3937D01*
G01X-76772Y3937D02*
G03X-72835Y0I3937J0D01*
G01X-76772Y35433D02*
G03X-80709Y39370I-3937J0D01*
G01X-76772Y35433D02*
G03X-80709Y39370I-3937J0D01*
G01X-76772Y3937D02*
G03X-72835Y0I3937J0D01*
G01X-76772Y3937D02*
Y35433D01*
G01Y3937D02*
Y35433D01*
G01Y3937D02*
G03X-72835Y0I3937J0D01*
G01X-84646Y7874D02*
Y0D01*
G01X-76772Y7874D02*
G03X-84646I-3937J0D01*
G01Y31496D02*
G03X-76772I3937J0D01*
G01Y3937D02*
G03X-72835Y0I3937J0D01*
G01X-84646Y7874D02*
Y0D01*
G01X-76772Y7874D02*
G03X-84646I-3937J0D01*
G01Y31496D02*
G03X-76772I3937J0D01*
G01X-76763Y1937008D02*
G03X-84638I-3937J0D01*
G01X-80709Y1929134D02*
G03X-76772Y1933071I0J3937D01*
G01X-80709Y1929134D02*
G03X-76772Y1933071I0J3937D01*
G01X-72835Y1968504D02*
G03X-76772Y1964567I0J-3937D01*
G01X-72835Y1968504D02*
G03X-76772Y1964567I0J-3937D01*
G01Y1933071D02*
Y1964567D01*
G01Y1933071D02*
Y1964567D01*
G01X-72835Y1968504D02*
G03X-76772Y1964567I0J-3937D01*
G01X-84638Y1960889D02*
Y1968504D01*
G01Y1960889D02*
G03X-76763I3938J0D01*
G01X-72835Y1968504D02*
G03X-76772Y1964567I0J-3937D01*
G01X-84638Y1960889D02*
Y1968504D01*
G01Y1960889D02*
G03X-76763I3938J0D01*
G01X-11811Y0D02*
X-72835D01*
G01X-11811D02*
X-72835D01*
G01D02*
X-11811D01*
G01X-72835D02*
X-11811D01*
G01X-72835Y1968504D02*
X-11811D01*
G01X-72835D02*
X-11811D01*
G01D02*
X-72835D01*
G01X-11811D02*
X-72835D01*
G01X-901Y-152763D02*
Y-135263D01*
X-3521Y-138763D01*
G01Y-152763D02*
X1719D01*
G01X12451Y-138180D02*
X13761Y-136430D01*
X15289Y-135555D01*
X17036Y-135263D01*
X19219Y-135846D01*
X20747Y-137305D01*
X21184Y-139054D01*
X20966Y-140805D01*
X20092Y-142263D01*
X15726Y-145180D01*
X13761Y-147221D01*
X12451Y-150139D01*
X12014Y-152763D01*
X21184D01*
G01X36719D02*
Y-135263D01*
X28640Y-147805D01*
X39558D01*
G01X46796Y-149263D02*
X48105Y-151305D01*
X49852Y-152471D01*
X51817Y-152763D01*
X53564Y-152471D01*
X55311Y-151013D01*
X56402Y-149263D01*
X56621Y-147513D01*
X56184Y-145472D01*
X54656Y-144013D01*
X53127Y-143430D01*
X51162D01*
G01X53127D02*
X54437Y-142555D01*
X55529Y-141097D01*
X55966Y-139347D01*
X55529Y-137596D01*
X54437Y-136138D01*
X52472Y-135263D01*
X50507Y-135555D01*
X48542Y-136722D01*
G01X64296Y-149263D02*
X65605Y-151305D01*
X67352Y-152471D01*
X69317Y-152763D01*
X71064Y-152471D01*
X72811Y-151013D01*
X73902Y-149263D01*
X74121Y-147513D01*
X73684Y-145472D01*
X72156Y-144013D01*
X70627Y-143430D01*
X68662D01*
G01X70627D02*
X71937Y-142555D01*
X73029Y-141097D01*
X73466Y-139347D01*
X73029Y-137596D01*
X71937Y-136138D01*
X69972Y-135263D01*
X68007Y-135555D01*
X66042Y-136722D01*
G01X-14018Y-107763D02*
Y-90263D01*
X-8778D01*
X-7031Y-91138D01*
X-5721Y-93180D01*
X-5284Y-95513D01*
X-5721Y-97846D01*
X-6813Y-99596D01*
X-8778Y-100472D01*
X-14018D01*
G01X12652Y-91722D02*
X11342Y-90846D01*
X9814Y-90263D01*
X8067D01*
X6102Y-91138D01*
X4574Y-92596D01*
X3482Y-94347D01*
X2609Y-97263D01*
X2390Y-99888D01*
X2827Y-102513D01*
X3482Y-104263D01*
X4792Y-106013D01*
X6321Y-107180D01*
X7849Y-107763D01*
X9377D01*
X10906Y-107180D01*
X12216Y-106305D01*
X13308Y-105139D01*
G01X27095Y-98430D02*
X27969Y-97555D01*
X28624Y-96097D01*
X29061Y-94054D01*
X28624Y-92305D01*
X27751Y-91138D01*
X26222Y-90263D01*
X20327D01*
Y-107763D01*
X27532D01*
X29061Y-106597D01*
X29934Y-104846D01*
X30371Y-102805D01*
X29934Y-100763D01*
X28624Y-99013D01*
X27095Y-98430D01*
X20327D01*
G01X36299Y-113596D02*
X49399D01*
G01X55327Y-107763D02*
Y-90263D01*
X65371Y-107763D01*
Y-90263D01*
G01X77849Y-107763D02*
X76102Y-107471D01*
X74574Y-106305D01*
X73264Y-104555D01*
X72390Y-102513D01*
X71954Y-100180D01*
Y-97846D01*
X72390Y-95513D01*
X73264Y-93471D01*
X74574Y-91722D01*
X76102Y-90555D01*
X77849Y-90263D01*
X79595Y-90555D01*
X81124Y-91722D01*
X82434Y-93471D01*
X83308Y-95513D01*
X83744Y-97846D01*
Y-100180D01*
X83308Y-102513D01*
X82434Y-104555D01*
X81124Y-106305D01*
X79595Y-107471D01*
X77849Y-107763D01*
G01X-11811Y0D02*
G03X-7874Y3937I0J3937D01*
G01X-11811Y0D02*
G03X-7874Y3937I0J3937D01*
G01Y43110D02*
Y3937D01*
G01Y43110D02*
Y3937D01*
G01X0D02*
G03X3937Y0I3937J0D01*
G01X0Y3937D02*
G03X3937Y0I3937J0D01*
G01X0Y3937D02*
Y43110D01*
G01Y3937D02*
Y43110D01*
G01X64961Y0D02*
X3937D01*
G01X64961D02*
X3937D01*
G01X0Y3937D02*
G03X3937Y0I3937J0D01*
G01X0Y1964567D02*
Y3937D01*
G01X3937Y0D02*
X64961D01*
G01X-7874Y3937D02*
Y1964567D01*
G01X-11811Y0D02*
G03X-7874Y3937I0J3937D01*
G01X0Y11811D02*
G03X-7874I-3937J0D01*
G01X0Y3937D02*
G03X3937Y0I3937J0D01*
G01X0Y1964567D02*
Y3937D01*
G01X3937Y0D02*
X64961D01*
G01X-7874Y3937D02*
Y1964567D01*
G01X-11811Y0D02*
G03X-7874Y3937I0J3937D01*
G01X0Y11811D02*
G03X-7874I-3937J0D01*
G01Y93110D02*
Y43110D01*
G01Y93110D02*
Y43110D01*
G01X0D02*
Y93110D01*
G01Y43110D02*
Y93110D01*
G01X-7874Y42520D02*
G03X0I3937J0D01*
G01X-7874D02*
G03X0I3937J0D01*
G01X-7874Y214764D02*
Y93110D01*
G01Y214764D02*
Y93110D01*
G01X0D02*
Y214764D01*
G01Y93110D02*
Y214764D01*
G01X-7874Y226968D02*
Y214764D01*
G01Y226968D02*
Y214764D01*
G01Y342461D02*
Y226968D01*
G01Y342461D02*
Y226968D01*
G01X0Y226969D02*
Y342461D01*
G01Y226969D02*
Y342461D01*
G01Y214764D02*
Y226969D01*
G01Y214764D02*
Y226969D01*
G01Y278740D02*
G03X-7874I-3937J0D01*
G01X0D02*
G03X-7874I-3937J0D01*
G01Y354665D02*
Y342461D01*
G01Y354665D02*
Y342461D01*
G01X0D02*
Y354665D01*
G01Y342461D02*
Y354665D01*
G01X-7874Y309449D02*
G03X0I3937J0D01*
G01X-7874D02*
G03X0I3937J0D01*
G01X-7874Y476339D02*
Y354665D01*
G01Y476339D02*
Y354665D01*
G01X0D02*
Y476339D01*
G01Y354665D02*
Y476339D01*
G01X-7874Y526339D02*
Y476339D01*
G01Y526339D02*
Y476339D01*
G01X0D02*
Y526339D01*
G01Y476339D02*
Y526339D01*
G01X-7874Y736181D02*
Y526339D01*
G01Y736181D02*
Y526339D01*
G01X0D02*
Y736181D01*
G01Y526339D02*
Y736181D01*
G01Y545669D02*
G03X-7874I-3937J0D01*
G01X0D02*
G03X-7874I-3937J0D01*
G01Y576378D02*
G03X0I3937J0D01*
G01X-7874D02*
G03X0I3937J0D01*
G01X-7874Y786181D02*
Y736181D01*
G01Y786181D02*
Y736181D01*
G01X0D02*
Y786181D01*
G01Y736181D02*
Y786181D01*
G01X-7874Y907815D02*
Y786181D01*
G01Y907815D02*
Y786181D01*
G01X0D02*
Y907815D01*
G01Y786181D02*
Y907815D01*
G01Y831496D02*
G03X-7874I-3937J0D01*
G01X0D02*
G03X-7874I-3937J0D01*
G01Y862205D02*
G03X0I3937J0D01*
G01X-7874D02*
G03X0I3937J0D01*
G01X-7874Y920020D02*
Y907815D01*
G01Y920020D02*
Y907815D01*
G01Y1048484D02*
Y920020D01*
G01Y1048484D02*
Y920020D01*
G01X0D02*
Y1048484D01*
G01Y920020D02*
Y1048484D01*
G01Y907815D02*
Y920020D01*
G01Y907815D02*
Y920020D01*
G01X-7874Y1060689D02*
Y1048484D01*
G01Y1060689D02*
Y1048484D01*
G01X0D02*
Y1060689D01*
G01Y1048484D02*
Y1060689D01*
G01X-7874Y1182323D02*
Y1060689D01*
G01Y1182323D02*
Y1060689D01*
G01X0D02*
Y1182323D01*
G01Y1060689D02*
Y1182323D01*
G01Y1106299D02*
G03X-7874I-3937J0D01*
G01X0D02*
G03X-7874I-3937J0D01*
G01Y1137008D02*
G03X0I3937J0D01*
G01X-7874D02*
G03X0I3937J0D01*
G01X-7874Y1232323D02*
Y1182323D01*
G01Y1232323D02*
Y1182323D01*
G01X0D02*
Y1232323D01*
G01Y1182323D02*
Y1232323D01*
G01X-7874Y1442165D02*
Y1232323D01*
G01Y1442165D02*
Y1232323D01*
G01X0D02*
Y1442165D01*
G01Y1232323D02*
Y1442165D01*
G01Y1392126D02*
G03X-7874I-3937J0D01*
G01X0D02*
G03X-7874I-3937J0D01*
G01Y1492165D02*
Y1442165D01*
G01Y1492165D02*
Y1442165D01*
G01X0D02*
Y1492165D01*
G01Y1442165D02*
Y1492165D01*
G01X-7874Y1422835D02*
G03X0I3937J0D01*
G01X-7874D02*
G03X0I3937J0D01*
G01X-7874Y1613839D02*
Y1492165D01*
G01Y1613839D02*
Y1492165D01*
G01X0D02*
Y1613839D01*
G01Y1492165D02*
Y1613839D01*
G01X-7874Y1626043D02*
Y1613839D01*
G01Y1626043D02*
Y1613839D01*
G01X0D02*
Y1626043D01*
G01Y1613839D02*
Y1626043D01*
G01X-7874Y1741535D02*
Y1626043D01*
G01Y1741535D02*
Y1626043D01*
G01X0D02*
Y1741535D01*
G01Y1626043D02*
Y1741535D01*
G01Y1659055D02*
G03X-7874I-3937J0D01*
G01X0D02*
G03X-7874I-3937J0D01*
G01Y1689764D02*
G03X0I3937J0D01*
G01X-7874D02*
G03X0I3937J0D01*
G01X-7874Y1753740D02*
Y1741535D01*
G01Y1753740D02*
Y1741535D01*
G01Y1875394D02*
Y1753740D01*
G01Y1875394D02*
Y1753740D01*
G01X0D02*
Y1875394D01*
G01Y1753740D02*
Y1875394D01*
G01Y1741535D02*
Y1753740D01*
G01Y1741535D02*
Y1753740D01*
G01X-7874Y1925394D02*
Y1875394D01*
G01Y1925394D02*
Y1875394D01*
G01X0D02*
Y1925394D01*
G01Y1875394D02*
Y1925394D01*
G01X-7874Y1964567D02*
Y1925394D01*
G01Y1964567D02*
Y1925394D01*
G01X0D02*
Y1964567D01*
G01Y1925394D02*
Y1964567D01*
G01Y1925984D02*
G03X-7874I-3937J0D01*
G01X0D02*
G03X-7874I-3937J0D01*
G01Y1964567D02*
G03X-11811Y1968504I-3937J0D01*
G01X-7874Y1964567D02*
G03X-11811Y1968504I-3937J0D01*
G01X3937D02*
G03X0Y1964567I0J-3937D01*
G01X3937Y1968504D02*
G03X0Y1964567I0J-3937D01*
G01X3937Y1968504D02*
X64961D01*
G01X3937D02*
X64961D01*
G01X3937D02*
G03X0Y1964567I0J-3937D01*
G01X64961Y1968504D02*
X3937D01*
G01X-7874Y1964567D02*
G03X-11811Y1968504I-3937J0D01*
G01X-7874Y1956693D02*
G03X0I3937J0D01*
G01X3937Y1968504D02*
G03X0Y1964567I0J-3937D01*
G01X64961Y1968504D02*
X3937D01*
G01X-7874Y1964567D02*
G03X-11811Y1968504I-3937J0D01*
G01X-7874Y1956693D02*
G03X0I3937J0D01*
G01X168110Y31496D02*
X76763D01*
G01X72835Y39370D02*
G03X68898Y35433I0J-3937D01*
G01X72835Y39370D02*
G03X68898Y35433I0J-3937D01*
G01X64961Y0D02*
G03X68898Y3937I0J3937D01*
G01X64961Y0D02*
G03X68898Y3937I0J3937D01*
G01Y35433D02*
Y3937D01*
G01Y35433D02*
Y3937D01*
G01X72835Y39370D02*
G03X68898Y35433I0J-3937D01*
G01Y3937D02*
Y35485D01*
G01X64961Y0D02*
G03X68898Y3937I0J3937D01*
G01X76763D02*
G03X80700Y0I3937J0D01*
G01X76763Y7615D02*
Y3937D01*
G01X168110Y31496D02*
X76763D01*
G01Y7615D02*
G03X68889I-3937J0D01*
G01Y31496D02*
G03X76763I3937J0D01*
G01X72835Y39370D02*
G03X68898Y35433I0J-3937D01*
G01Y3937D02*
Y35485D01*
G01X64961Y0D02*
G03X68898Y3937I0J3937D01*
G01X76763D02*
G03X80700Y0I3937J0D01*
G01X76763Y7615D02*
Y3937D01*
G01X168110Y31496D02*
X76763D01*
G01Y7615D02*
G03X68889I-3937J0D01*
G01Y31496D02*
G03X76763I3937J0D01*
G01X202756Y39370D02*
X72835D01*
G01X202756D02*
X72835D01*
G01D02*
X202756D01*
G01X72835D02*
X202756D01*
G01X68898Y1964567D02*
G03X64961Y1968504I-3937J0D01*
G01X68898Y1933071D02*
G03X72835Y1929134I3937J0D01*
G01X68898Y1933071D02*
G03X72835Y1929134I3937J0D01*
G01X68898Y1964567D02*
G03X64961Y1968504I-3937J0D01*
G01X72835Y1929134D02*
X202756D01*
G01X72835D02*
X202756D01*
G01X68898Y1964567D02*
Y1933071D01*
G01Y1964567D02*
Y1933071D01*
G01Y1964567D02*
G03X64961Y1968504I-3937J0D01*
G01X68898Y1933071D02*
Y1964567D01*
G01Y1933071D02*
G03X72835Y1929134I3937J0D01*
G01X202756D02*
X72835D01*
G01X80709Y1968504D02*
G03X76772Y1964567I0J-3937D01*
G01Y1960630D02*
Y1964567D01*
G01X168110Y1937008D02*
X76772D01*
G01X68898Y1960630D02*
G03X76772I3937J0D01*
G01Y1937008D02*
G03X68898I-3937J0D01*
G01Y1964567D02*
G03X64961Y1968504I-3937J0D01*
G01X68898Y1933071D02*
Y1964567D01*
G01Y1933071D02*
G03X72835Y1929134I3937J0D01*
G01X202756D02*
X72835D01*
G01X80709Y1968504D02*
G03X76772Y1964567I0J-3937D01*
G01Y1960630D02*
Y1964567D01*
G01X168110Y1937008D02*
X76772D01*
G01X68898Y1960630D02*
G03X76772I3937J0D01*
G01Y1937008D02*
G03X68898I-3937J0D01*
G01X128690Y-90263D02*
X134149Y-107763D01*
X139608Y-90263D01*
G01X156016Y-107763D02*
X147282D01*
Y-90263D01*
X156016D01*
G01X152522Y-98721D02*
X147282D01*
G01X164782Y-107763D02*
Y-90263D01*
X170241D01*
X171987Y-91138D01*
X173079Y-92305D01*
X173516Y-94638D01*
X173079Y-96972D01*
X171769Y-98430D01*
X170241Y-99305D01*
X164782D01*
G01X170241D02*
X173516Y-107763D01*
G01X186649Y-108346D02*
X186212Y-108055D01*
Y-107471D01*
X186649Y-107180D01*
X187086Y-107471D01*
Y-108055D01*
X186649Y-108346D01*
G01X80700Y0D02*
X340551D01*
G01X80700D02*
X340551D01*
G01X118011Y1968504D02*
X142520D01*
G01X109377D02*
X110137D01*
G01X109377D02*
X80709D01*
G01X110137D02*
G03X118011I3937J0D01*
G01X109377D02*
X80709D01*
G01X110137D02*
G03X118011I3937J0D01*
G01X151649Y-152763D02*
Y-135263D01*
X149029Y-138763D01*
G01Y-152763D02*
X154269D01*
G01X163472D02*
Y-135263D01*
X169149Y-149846D01*
X174826Y-135263D01*
Y-152763D01*
G01X168110Y31496D02*
G03Y39370I0J3937D01*
G01Y31496D02*
G03Y39370I0J3937D01*
G01X340559Y1968504D02*
X142520D01*
G01X168110Y1929134D02*
G03Y1937008I0J3937D01*
G01X340559Y1968504D02*
X142520D01*
G01X168110Y1929134D02*
G03Y1937008I0J3937D01*
G01X222441Y31496D02*
X198819D01*
G01X222441D02*
G03Y39370I0J3937D01*
G01X198819D02*
G03Y31496I0J-3937D01*
G01X222441D02*
X198819D01*
G01X222441D02*
G03Y39370I0J3937D01*
G01X198819D02*
G03Y31496I0J-3937D01*
G01X214567Y161417D02*
Y43307D01*
G01X202756Y39370D02*
G03X206693Y43307I0J3937D01*
G01X202756Y39370D02*
G03X206693Y43307I0J3937D01*
G01Y1925197D02*
Y43307D01*
G01Y1925197D02*
Y43307D01*
G01X202756Y39370D02*
G03X206693Y43307I0J3937D01*
G01X218504Y39370D02*
X348425D01*
G01X214567Y43307D02*
G03X218504Y39370I3937J0D01*
G01X202756D02*
G03X206693Y43307I0J3937D01*
G01X218504Y39370D02*
X348425D01*
G01X214567Y43307D02*
G03X218504Y39370I3937J0D01*
G01X206693Y161417D02*
Y1807087D01*
G01X214567D02*
Y161417D01*
G01Y169291D02*
G03X206693I-3937J0D01*
G01Y161417D02*
Y1807087D01*
G01X214567D02*
Y161417D01*
G01Y169291D02*
G03X206693I-3937J0D01*
G01Y200000D02*
G03X214567I3937J0D01*
G01X206693D02*
G03X214567I3937J0D01*
G01Y436220D02*
G03X206693I-3937J0D01*
G01X214567D02*
G03X206693I-3937J0D01*
G01Y466929D02*
G03X214567I3937J0D01*
G01X206693D02*
G03X214567I3937J0D01*
G01Y703149D02*
G03X206693I-3937J0D01*
G01Y733858D02*
G03X214567I3937J0D01*
G01Y703149D02*
G03X206693I-3937J0D01*
G01Y733858D02*
G03X214567I3937J0D01*
G01Y970867D02*
G03X206693I-3937J0D01*
G01Y997637D02*
G03X214567I3937J0D01*
G01Y970867D02*
G03X206693I-3937J0D01*
G01Y997637D02*
G03X214567I3937J0D01*
G01X206693Y1265355D02*
G03X214567I3937J0D01*
G01Y1234646D02*
G03X206693I-3937J0D01*
G01Y1265355D02*
G03X214567I3937J0D01*
G01Y1234646D02*
G03X206693I-3937J0D01*
G01X214567Y1501575D02*
G03X206693I-3937J0D01*
G01X214567D02*
G03X206693I-3937J0D01*
G01Y1532284D02*
G03X214567I3937J0D01*
G01X206693D02*
G03X214567I3937J0D01*
G01Y1768504D02*
G03X206693I-3937J0D01*
G01X214567D02*
G03X206693I-3937J0D01*
G01X214567Y1807087D02*
Y1925197D01*
G01X206693Y1799213D02*
G03X214567I3937J0D01*
G01X206693D02*
G03X214567I3937J0D01*
G01X206693Y1925197D02*
G03X202756Y1929134I-3937J0D01*
G01X206693Y1925197D02*
G03X202756Y1929134I-3937J0D01*
G01X206693Y1925197D02*
G03X202756Y1929134I-3937J0D01*
G01X218504D02*
G03X214567Y1925197I0J-3937D01*
G01X206693D02*
G03X202756Y1929134I-3937J0D01*
G01X218504D02*
G03X214567Y1925197I0J-3937D01*
G01X348425Y1929134D02*
X218504D01*
G01X198819Y1937008D02*
X222441D01*
G01X198819D02*
G03Y1929134I0J-3937D01*
G01X222441D02*
G03Y1937008I0J3937D01*
G01X348425Y1929134D02*
X218504D01*
G01X198819Y1937008D02*
X222441D01*
G01X198819D02*
G03Y1929134I0J-3937D01*
G01X222441D02*
G03Y1937008I0J3937D01*
G01X259159Y-144013D02*
X263526D01*
Y-149263D01*
X262216Y-151013D01*
X260687Y-152180D01*
X258504Y-152763D01*
X256321Y-152180D01*
X254792Y-151013D01*
X253482Y-149263D01*
X252609Y-147221D01*
X252172Y-144888D01*
Y-142846D01*
X252609Y-141097D01*
X253482Y-139054D01*
X254792Y-137305D01*
X256102Y-136138D01*
X257849Y-135263D01*
X259377D01*
X261124Y-135846D01*
X262434Y-137013D01*
G01X275349Y-152763D02*
X273602Y-152471D01*
X272074Y-151305D01*
X270764Y-149555D01*
X269890Y-147513D01*
X269454Y-145180D01*
Y-142846D01*
X269890Y-140513D01*
X270764Y-138471D01*
X272074Y-136722D01*
X273602Y-135555D01*
X275349Y-135263D01*
X277095Y-135555D01*
X278624Y-136722D01*
X279934Y-138471D01*
X280808Y-140513D01*
X281244Y-142846D01*
Y-145180D01*
X280808Y-147513D01*
X279934Y-149555D01*
X278624Y-151305D01*
X277095Y-152471D01*
X275349Y-152763D01*
G01X288482Y-135263D02*
Y-152763D01*
X297216D01*
G01X305546D02*
Y-135263D01*
X309912D01*
X311659Y-136138D01*
X312969Y-137305D01*
X314061Y-139054D01*
X314934Y-141097D01*
X315152Y-144013D01*
X314934Y-146930D01*
X314061Y-148972D01*
X312969Y-150722D01*
X311659Y-151888D01*
X309912Y-152763D01*
X305546D01*
G01X321299Y-158596D02*
X334399D01*
G01X345349Y-135263D02*
Y-152763D01*
G01X340327Y-135263D02*
X350371D01*
G01X253482Y-90263D02*
Y-107763D01*
X262216D01*
G01X279279D02*
Y-96097D01*
G01Y-98138D02*
X278406Y-96972D01*
X277095Y-96388D01*
X275567Y-96097D01*
X274039Y-96680D01*
X272729Y-97846D01*
X271855Y-99596D01*
X271419Y-101930D01*
X271855Y-104263D01*
X272729Y-106013D01*
X274039Y-107180D01*
X275567Y-107763D01*
X277095Y-107471D01*
X278406Y-106597D01*
X279279Y-105430D01*
G01X288264Y-113013D02*
X289574Y-113596D01*
X291321Y-113013D01*
X292412Y-111847D01*
X293286Y-110388D01*
X294595Y-105722D01*
X297434Y-96097D01*
G01X290447D02*
X294595Y-105722D01*
G01X307074Y-99888D02*
X314061D01*
X313406Y-97846D01*
X312314Y-96680D01*
X310786Y-96097D01*
X309257Y-96388D01*
X307947Y-97263D01*
X307074Y-99305D01*
X306637Y-101055D01*
Y-102805D01*
X307074Y-104555D01*
X308166Y-106305D01*
X309476Y-107471D01*
X311004Y-107763D01*
X312532Y-107180D01*
X314061Y-105430D01*
G01X324792Y-107763D02*
Y-96097D01*
G01Y-98430D02*
X325884Y-97263D01*
X326976Y-96388D01*
X328504Y-96097D01*
X329595Y-96388D01*
X330906Y-97263D01*
G01X342074Y-105722D02*
X343166Y-106888D01*
X344694Y-107763D01*
X346004D01*
X347314Y-107180D01*
X348187Y-106305D01*
X348624Y-105139D01*
X348406Y-103388D01*
X347532Y-102513D01*
X343602Y-100763D01*
X342729Y-98721D01*
X343166Y-97263D01*
X344039Y-96388D01*
X345349Y-96097D01*
X346659Y-96388D01*
X347969Y-97263D01*
G01X253150Y31496D02*
X344488D01*
G01X253150Y39370D02*
G03Y31496I0J-3937D01*
G01D02*
X344488D01*
G01X253150Y39370D02*
G03Y31496I0J-3937D01*
G01Y1937008D02*
X344496D01*
G01X253150D02*
G03Y1929134I0J-3937D01*
G01Y1937008D02*
X344496D01*
G01X253150D02*
G03Y1929134I0J-3937D01*
G01X356299Y0D02*
X417323D01*
G01X352362Y3937D02*
G03X356299Y0I3937J0D01*
G01X352362Y35433D02*
Y3937D01*
G01Y35433D02*
G03X348425Y39370I-3937J0D01*
G01X340551Y0D02*
G03X344488Y3937I0J3937D01*
G01Y7874D02*
Y3937D01*
G01X352362Y7874D02*
G03X344488I-3937J0D01*
G01Y31496D02*
G03X352362I3937J0D01*
G01X356299Y0D02*
X417323D01*
G01X352362Y3937D02*
G03X356299Y0I3937J0D01*
G01X352362Y35433D02*
Y3937D01*
G01Y35433D02*
G03X348425Y39370I-3937J0D01*
G01X340551Y0D02*
G03X344488Y3937I0J3937D01*
G01Y7874D02*
Y3937D01*
G01X352362Y7874D02*
G03X344488I-3937J0D01*
G01Y31496D02*
G03X352362I3937J0D01*
G01X348425Y1929134D02*
G03X352362Y1933071I0J3937D01*
G01Y1964567D02*
Y1933071D01*
G01X356299Y1968504D02*
G03X352362Y1964567I0J-3937D01*
G01X417323Y1968504D02*
X356299D01*
G01X344496Y1964567D02*
G03X340559Y1968504I-3937J0D01*
G01X344496Y1960889D02*
Y1964567D01*
G01Y1960889D02*
G03X352370I3937J0D01*
G01Y1937008D02*
G03X344496I-3937J0D01*
G01X348425Y1929134D02*
G03X352362Y1933071I0J3937D01*
G01Y1964567D02*
Y1933071D01*
G01X356299Y1968504D02*
G03X352362Y1964567I0J-3937D01*
G01X417323Y1968504D02*
X356299D01*
G01X344496Y1964567D02*
G03X340559Y1968504I-3937J0D01*
G01X344496Y1960889D02*
Y1964567D01*
G01Y1960889D02*
G03X352370I3937J0D01*
G01Y1937008D02*
G03X344496I-3937J0D01*
G01X404346Y-107763D02*
Y-90263D01*
X408712D01*
X410459Y-91138D01*
X411769Y-92305D01*
X412861Y-94054D01*
X413734Y-96097D01*
X413952Y-99013D01*
X413734Y-101930D01*
X412861Y-103972D01*
X411769Y-105722D01*
X410459Y-106888D01*
X408712Y-107763D01*
X404346D01*
G01X423374Y-99888D02*
X430361D01*
X429706Y-97846D01*
X428614Y-96680D01*
X427086Y-96097D01*
X425557Y-96388D01*
X424247Y-97263D01*
X423374Y-99305D01*
X422937Y-101055D01*
Y-102805D01*
X423374Y-104555D01*
X424466Y-106305D01*
X425776Y-107471D01*
X427304Y-107763D01*
X428832Y-107180D01*
X430361Y-105430D01*
G01X440874Y-105722D02*
X441966Y-106888D01*
X443494Y-107763D01*
X444804D01*
X446114Y-107180D01*
X446987Y-106305D01*
X447424Y-105139D01*
X447206Y-103388D01*
X446332Y-102513D01*
X442402Y-100763D01*
X441529Y-98721D01*
X441966Y-97263D01*
X442839Y-96388D01*
X444149Y-96097D01*
X445459Y-96388D01*
X446769Y-97263D01*
G01X461649Y-96097D02*
Y-107763D01*
G01Y-91430D02*
X461212Y-91138D01*
Y-90555D01*
X461649Y-90263D01*
X462086Y-90555D01*
Y-91138D01*
X461649Y-91430D01*
G01X476092Y-112138D02*
X477621Y-113305D01*
X479367Y-113596D01*
X480895Y-113305D01*
X482206Y-111847D01*
X483079Y-109805D01*
Y-96097D01*
G01Y-98430D02*
X482206Y-97263D01*
X480895Y-96388D01*
X479367Y-96097D01*
X477621Y-96680D01*
X476529Y-97846D01*
X475655Y-99888D01*
X475219Y-101930D01*
X475437Y-103680D01*
X476311Y-105722D01*
X477621Y-107180D01*
X479367Y-107763D01*
X480677Y-107471D01*
X482206Y-106305D01*
X483079Y-105139D01*
G01X492937Y-107763D02*
Y-96097D01*
G01Y-99013D02*
X493811Y-97555D01*
X495121Y-96388D01*
X496867Y-96097D01*
X498395Y-96388D01*
X499706Y-97555D01*
X500361Y-99596D01*
Y-107763D01*
G01X510874Y-99888D02*
X517861D01*
X517206Y-97846D01*
X516114Y-96680D01*
X514586Y-96097D01*
X513057Y-96388D01*
X511747Y-97263D01*
X510874Y-99305D01*
X510437Y-101055D01*
Y-102805D01*
X510874Y-104555D01*
X511966Y-106305D01*
X513276Y-107471D01*
X514804Y-107763D01*
X516332Y-107180D01*
X517861Y-105430D01*
G01X528592Y-107763D02*
Y-96097D01*
G01Y-98430D02*
X529684Y-97263D01*
X530776Y-96388D01*
X532304Y-96097D01*
X533395Y-96388D01*
X534706Y-97263D01*
G01X429134Y3937D02*
G03X433071Y0I3937J0D01*
G01X429134Y1964567D02*
Y3937D01*
G01X433071Y0D02*
X494095D01*
G01X421260Y3937D02*
Y1964567D01*
G01X417323Y0D02*
G03X421260Y3937I0J3937D01*
G01X429134Y11811D02*
G03X421260I-3937J0D01*
G01X429134Y3937D02*
G03X433071Y0I3937J0D01*
G01X429134Y1964567D02*
Y3937D01*
G01X433071Y0D02*
X494095D01*
G01X421260Y3937D02*
Y1964567D01*
G01X417323Y0D02*
G03X421260Y3937I0J3937D01*
G01X429134Y11811D02*
G03X421260I-3937J0D01*
G01Y42520D02*
G03X429134I3937J0D01*
G01X421260D02*
G03X429134I3937J0D01*
G01Y278740D02*
G03X421260I-3937J0D01*
G01X429134D02*
G03X421260I-3937J0D01*
G01Y309449D02*
G03X429134I3937J0D01*
G01X421260D02*
G03X429134I3937J0D01*
G01Y545669D02*
G03X421260I-3937J0D01*
G01X429134D02*
G03X421260I-3937J0D01*
G01Y576378D02*
G03X429134I3937J0D01*
G01X421260D02*
G03X429134I3937J0D01*
G01Y831496D02*
G03X421260I-3937J0D01*
G01X429134D02*
G03X421260I-3937J0D01*
G01Y862205D02*
G03X429134I3937J0D01*
G01X421260D02*
G03X429134I3937J0D01*
G01Y1106299D02*
G03X421260I-3937J0D01*
G01X429134D02*
G03X421260I-3937J0D01*
G01Y1137008D02*
G03X429134I3937J0D01*
G01X421260D02*
G03X429134I3937J0D01*
G01Y1392126D02*
G03X421260I-3937J0D01*
G01X429134D02*
G03X421260I-3937J0D01*
G01Y1422835D02*
G03X429134I3937J0D01*
G01X421260D02*
G03X429134I3937J0D01*
G01Y1659055D02*
G03X421260I-3937J0D01*
G01X429134D02*
G03X421260I-3937J0D01*
G01Y1689764D02*
G03X429134I3937J0D01*
G01X421260D02*
G03X429134I3937J0D01*
G01Y1925984D02*
G03X421260I-3937J0D01*
G01X429134D02*
G03X421260I-3937J0D01*
G01X433071Y1968504D02*
G03X429134Y1964567I0J-3937D01*
G01X494095Y1968504D02*
X433071D01*
G01X421260Y1964567D02*
G03X417323Y1968504I-3937J0D01*
G01X421260Y1956693D02*
G03X429134I3937J0D01*
G01X433071Y1968504D02*
G03X429134Y1964567I0J-3937D01*
G01X494095Y1968504D02*
X433071D01*
G01X421260Y1964567D02*
G03X417323Y1968504I-3937J0D01*
G01X421260Y1956693D02*
G03X429134I3937J0D01*
G01X433071Y1968504D02*
G03X429134Y1964567I0J-3937D01*
G01X421260D02*
G03X417323Y1968504I-3937J0D01*
G01X448096Y-152763D02*
Y-135263D01*
X452462D01*
X454209Y-136138D01*
X455519Y-137305D01*
X456611Y-139054D01*
X457484Y-141097D01*
X457702Y-144013D01*
X457484Y-146930D01*
X456611Y-148972D01*
X455519Y-150722D01*
X454209Y-151888D01*
X452462Y-152763D01*
X448096D01*
G01X470399Y-141097D02*
Y-152763D01*
G01Y-136430D02*
X469962Y-136138D01*
Y-135555D01*
X470399Y-135263D01*
X470836Y-135555D01*
Y-136138D01*
X470399Y-136430D01*
G01X487899Y-152763D02*
X486589Y-152471D01*
X485279Y-151305D01*
X484405Y-149263D01*
X483969Y-146930D01*
X484405Y-144596D01*
X485279Y-142555D01*
X486589Y-141388D01*
X487899Y-141097D01*
X489209Y-141388D01*
X490519Y-142555D01*
X491392Y-144596D01*
X491611Y-146930D01*
X491392Y-149263D01*
X490519Y-151305D01*
X489209Y-152471D01*
X487899Y-152763D01*
G01X501969Y39370D02*
G03X498032Y35433I0J-3937D01*
G01Y3937D02*
Y35433D01*
G01X494095Y0D02*
G03X498032Y3937I0J3937D01*
G01X505897Y0D02*
X648386D01*
G01X505897Y7615D02*
Y0D01*
G01X597244Y31496D02*
X505897D01*
G01Y7615D02*
G03X498023I-3937J0D01*
G01Y31496D02*
G03X505897I3937J0D01*
G01X501969Y39370D02*
G03X498032Y35433I0J-3937D01*
G01Y3937D02*
Y35433D01*
G01X494095Y0D02*
G03X498032Y3937I0J3937D01*
G01X505897Y0D02*
X620827D01*
G01X505897Y7615D02*
Y0D01*
G01X597244Y31496D02*
X505897D01*
G01Y7615D02*
G03X498023I-3937J0D01*
G01Y31496D02*
G03X505897I3937J0D01*
G01X501969Y39370D02*
X631890D01*
G01X501969D02*
X631890D01*
G01X498032Y1964567D02*
G03X494095Y1968504I-3937J0D01*
G01X498032Y1933071D02*
Y1960630D01*
G01Y1933071D02*
G03X501969Y1929134I3937J0D01*
G01X631890D02*
X501969D01*
G01X505906Y1960630D02*
Y1968504D01*
G01D02*
X648386D01*
G01X597244Y1937008D02*
X505906D01*
G01X498032Y1960630D02*
G03X505906I3937J0D01*
G01Y1937008D02*
G03X498032I-3937J0D01*
G01Y1964567D02*
G03X494095Y1968504I-3937J0D01*
G01X498032Y1933071D02*
Y1964567D01*
G01Y1933071D02*
G03X501969Y1929134I3937J0D01*
G01X631890D02*
X501969D01*
G01X505906Y1960630D02*
Y1968504D01*
G01D02*
X620827D01*
G01X597244Y1937008D02*
X505906D01*
G01X498032Y1960630D02*
G03X505906I3937J0D01*
G01Y1937008D02*
G03X498032I-3937J0D01*
G01X575349Y-152763D02*
Y-135263D01*
X572729Y-138763D01*
G01Y-152763D02*
X577969D01*
G01X588701Y-138180D02*
X590011Y-136430D01*
X591539Y-135555D01*
X593286Y-135263D01*
X595469Y-135846D01*
X596997Y-137305D01*
X597434Y-139054D01*
X597216Y-140805D01*
X596342Y-142263D01*
X591976Y-145180D01*
X590011Y-147221D01*
X588701Y-150139D01*
X588264Y-152763D01*
X597434D01*
G01X606419Y-153346D02*
X614279Y-135263D01*
G01X627849D02*
X626102Y-135846D01*
X624792Y-137305D01*
X623919Y-139054D01*
X623264Y-141388D01*
X623046Y-144013D01*
X623264Y-146638D01*
X623919Y-148972D01*
X624792Y-150722D01*
X626102Y-152180D01*
X627849Y-152763D01*
X629595Y-152180D01*
X630906Y-150722D01*
X631779Y-148972D01*
X632434Y-146638D01*
X632652Y-144013D01*
X632434Y-141388D01*
X631779Y-139054D01*
X630906Y-137305D01*
X629595Y-135846D01*
X627849Y-135263D01*
G01X644912Y-152763D02*
X645349Y-148972D01*
X646004Y-145763D01*
X646877Y-142846D01*
X647969Y-139638D01*
X649716Y-135263D01*
X640982D01*
G01X658919Y-153346D02*
X666779Y-135263D01*
G01X676201Y-138180D02*
X677511Y-136430D01*
X679039Y-135555D01*
X680786Y-135263D01*
X682969Y-135846D01*
X684497Y-137305D01*
X684934Y-139054D01*
X684716Y-140805D01*
X683842Y-142263D01*
X679476Y-145180D01*
X677511Y-147221D01*
X676201Y-150139D01*
X675764Y-152763D01*
X684934D01*
G01X697849Y-135263D02*
X696102Y-135846D01*
X694792Y-137305D01*
X693919Y-139054D01*
X693264Y-141388D01*
X693046Y-144013D01*
X693264Y-146638D01*
X693919Y-148972D01*
X694792Y-150722D01*
X696102Y-152180D01*
X697849Y-152763D01*
X699595Y-152180D01*
X700906Y-150722D01*
X701779Y-148972D01*
X702434Y-146638D01*
X702652Y-144013D01*
X702434Y-141388D01*
X701779Y-139054D01*
X700906Y-137305D01*
X699595Y-135846D01*
X697849Y-135263D01*
G01X715349Y-152763D02*
Y-135263D01*
X712729Y-138763D01*
G01Y-152763D02*
X717969D01*
G01X728701Y-138180D02*
X730011Y-136430D01*
X731539Y-135555D01*
X733286Y-135263D01*
X735469Y-135846D01*
X736997Y-137305D01*
X737434Y-139054D01*
X737216Y-140805D01*
X736342Y-142263D01*
X731976Y-145180D01*
X730011Y-147221D01*
X728701Y-150139D01*
X728264Y-152763D01*
X737434D01*
G01X623046Y-107763D02*
Y-90263D01*
X627412D01*
X629159Y-91138D01*
X630469Y-92305D01*
X631561Y-94054D01*
X632434Y-96097D01*
X632652Y-99013D01*
X632434Y-101930D01*
X631561Y-103972D01*
X630469Y-105722D01*
X629159Y-106888D01*
X627412Y-107763D01*
X623046D01*
G01X649279D02*
Y-96097D01*
G01Y-98138D02*
X648406Y-96972D01*
X647095Y-96388D01*
X645567Y-96097D01*
X644039Y-96680D01*
X642729Y-97846D01*
X641855Y-99596D01*
X641419Y-101930D01*
X641855Y-104263D01*
X642729Y-106013D01*
X644039Y-107180D01*
X645567Y-107763D01*
X647095Y-107471D01*
X648406Y-106597D01*
X649279Y-105430D01*
G01X662849Y-90263D02*
Y-107763D01*
G01X659792Y-96097D02*
X665906D01*
G01X677074Y-99888D02*
X684061D01*
X683406Y-97846D01*
X682314Y-96680D01*
X680786Y-96097D01*
X679257Y-96388D01*
X677947Y-97263D01*
X677074Y-99305D01*
X676637Y-101055D01*
Y-102805D01*
X677074Y-104555D01*
X678166Y-106305D01*
X679476Y-107471D01*
X681004Y-107763D01*
X682532Y-107180D01*
X684061Y-105430D01*
G01X635827Y31496D02*
G03X643701Y39370I0J7874D01*
G01X650689Y19685D02*
G03I-6988J0D01*
G01X635827Y31496D02*
X627953D01*
G01X597244D02*
G03Y39370I0J3937D01*
G01X627953D02*
G03Y31496I0J-3937D01*
G01X650689Y19685D02*
G03I-6988J0D01*
G01X635827Y31496D02*
X627953D01*
G01X597244D02*
G03Y39370I0J3937D01*
G01X627953D02*
G03Y31496I0J-3937D01*
G01X635827Y161417D02*
Y43307D01*
G01X631890Y39370D02*
G03X635827Y43307I0J3937D01*
G01X631890Y39370D02*
G03X635827Y43307I0J3937D01*
G01X643701Y169256D02*
G03X635827I-3937J0D01*
G01X643701D02*
G03X635827I-3937J0D01*
G01Y161417D02*
Y1807087D01*
G01Y161417D02*
Y1807087D01*
G01Y199965D02*
G03X643701I3937J0D01*
G01X635827D02*
G03X643701I3937J0D01*
G01Y436186D02*
G03X635827I-3937J0D01*
G01X643701D02*
G03X635827I-3937J0D01*
G01Y466894D02*
G03X643701I3937J0D01*
G01X635827D02*
G03X643701I3937J0D01*
G01Y703115D02*
G03X635827I-3937J0D01*
G01Y733823D02*
G03X643701I3937J0D01*
G01Y703115D02*
G03X635827I-3937J0D01*
G01Y733823D02*
G03X643701I3937J0D01*
G01X635827Y997603D02*
G03X643701I3937J0D01*
G01Y970832D02*
G03X635827I-3937J0D01*
G01Y997603D02*
G03X643701I3937J0D01*
G01Y970832D02*
G03X635827I-3937J0D01*
G01Y1265320D02*
G03X643701I3937J0D01*
G01Y1234611D02*
G03X635827I-3937J0D01*
G01Y1265320D02*
G03X643701I3937J0D01*
G01Y1234611D02*
G03X635827I-3937J0D01*
G01X643701Y1501541D02*
G03X635827I-3937J0D01*
G01X643701D02*
G03X635827I-3937J0D01*
G01Y1532249D02*
G03X643701I3937J0D01*
G01X635827D02*
G03X643701I3937J0D01*
G01Y1768470D02*
G03X635827I-3937J0D01*
G01X643701D02*
G03X635827I-3937J0D01*
G01Y1799178D02*
G03X643701I3937J0D01*
G01X635827D02*
G03X643701I3937J0D01*
G01X635827Y1818898D02*
Y1807087D01*
G01Y1818898D02*
Y1925197D01*
G01Y1818898D02*
Y1925197D01*
G01D02*
G03X631890Y1929134I-3937J0D01*
G01X635827Y1925197D02*
G03X631890Y1929134I-3937J0D01*
G01X643701D02*
G03X635827Y1937008I-7874J0D01*
G01X650689Y1948819D02*
G03I-6988J0D01*
G01X627953Y1937008D02*
X635827D01*
G01X627953D02*
G03Y1929134I0J-3937D01*
G01X597244D02*
G03Y1937008I0J3937D01*
G01X650689Y1948819D02*
G03I-6988J0D01*
G01X627953Y1937008D02*
X635827D01*
G01X627953D02*
G03Y1929134I0J-3937D01*
G01X597244D02*
G03Y1937008I0J3937D01*
G01X650689Y1948819D02*
G03I-6988J0D01*
G01X648386Y0D02*
G03X663386Y15000I0J15000D01*
G01Y1953504D02*
Y15000D01*
G01X643701Y169256D02*
Y39370D01*
G01Y436186D02*
Y199965D01*
G01Y703115D02*
Y466894D01*
G01Y970832D02*
Y733823D01*
G01Y1234611D02*
Y997603D01*
G01Y1501541D02*
Y1265320D01*
G01Y1768470D02*
Y1532249D01*
G01Y1929134D02*
Y1799178D01*
G01X663386Y1953504D02*
G03X648386Y1968504I-15000J0D01*
M02*
